(kicad_pcb
	(version 20240108)
	(generator "pcbnew")
	(generator_version "8.0")
	(general
		(thickness 1.62)
		(legacy_teardrops no)
	)
	(paper "A4")
	(title_block
		(title "Jetson Orin Baseboard")
		(date "2025-03-12")
		(rev "1.3.4")
		(company "Antmicro Ltd")
		(comment 1 "www.antmicro.com")
		(comment 9 "footprints 640-644 of 677")
	)
	(layers
		(0 "F.Cu" signal)
		(1 "In1.Cu" signal)
		(2 "In2.Cu" signal)
		(3 "In3.Cu" signal)
		(4 "In4.Cu" jumper)
		(5 "In5.Cu" signal)
		(6 "In6.Cu" signal)
		(31 "B.Cu" signal)
		(32 "B.Adhes" user "B.Adhesive")
		(33 "F.Adhes" user "F.Adhesive")
		(34 "B.Paste" user)
		(35 "F.Paste" user)
		(36 "B.SilkS" user "B.Silkscreen")
		(37 "F.SilkS" user "F.Silkscreen")
		(38 "B.Mask" user)
		(39 "F.Mask" user)
		(40 "Dwgs.User" user "User.Drawings")
		(41 "Cmts.User" user "User.Comments")
		(42 "Eco1.User" user "User.Eco1")
		(43 "Eco2.User" user "User.Eco2")
		(44 "Edge.Cuts" user)
		(45 "Margin" user)
		(46 "B.CrtYd" user "B.Courtyard")
		(47 "F.CrtYd" user "F.Courtyard")
		(48 "B.Fab" user)
		(49 "F.Fab" user)
	)
	(footprint "antmicro-footprints:R_0402_1005Metric"
		(layer "B.Cu")
		(at 76 103.4 90)
		(descr "Resistor SMD 0402")
		(tags "resistor SMD 0402")
		(property "Reference" "R87"
			(at 5.16 1.67 -90)
			(layer "B.SilkS")
			(effects
				(font
					(size 0.7 0.7)
					(thickness 0.15)
				)
				(justify left bottom mirror)
			)
		)
		(property "Value" "R_1k_0402"
			(at 0 -1.4 -90)
			(layer "B.Fab")
			(effects
				(font
					(size 0.7 0.7)
					(thickness 0.15)
				)
				(justify left bottom mirror)
			)
		)
		(property "Footprint" "antmicro-footprints:R_0402_1005Metric"
			(at 0 0 90)
			(layer "F.Fab")
			(hide yes)
			(effects
				(font
					(size 1.27 1.27)
					(thickness 0.15)
				)
			)
		)
		(property "Datasheet" "https://www.bourns.com/docs/product-datasheets/cr.pdf"
			(at 0 0 90)
			(layer "F.Fab")
			(hide yes)
			(effects
				(font
					(size 1.27 1.27)
					(thickness 0.15)
				)
			)
		)
		(property "Author" "Antmicro"
			(at 179.4 27.4 0)
			(layer "B.Fab")
			(hide yes)
			(effects
				(font
					(size 1 1)
					(thickness 0.15)
				)
				(justify mirror)
			)
		)
		(property "License" "Apache-2.0"
			(at 179.4 27.4 0)
			(layer "B.Fab")
			(hide yes)
			(effects
				(font
					(size 1 1)
					(thickness 0.15)
				)
				(justify mirror)
			)
		)
		(property "MPN" "CR0402-FX-1001GLF"
			(at 179.4 27.4 0)
			(layer "B.Fab")
			(hide yes)
			(effects
				(font
					(size 1 1)
					(thickness 0.15)
				)
				(justify mirror)
			)
		)
		(property "Manufacturer" "Bourns"
			(at 179.4 27.4 0)
			(layer "B.Fab")
			(hide yes)
			(effects
				(font
					(size 1 1)
					(thickness 0.15)
				)
				(justify mirror)
			)
		)
		(property "Tolerance" "1%"
			(at 179.4 27.4 0)
			(layer "B.Fab")
			(hide yes)
			(effects
				(font
					(size 1 1)
					(thickness 0.15)
				)
				(justify mirror)
			)
		)
		(property "Val" "1k"
			(at 179.4 27.4 0)
			(layer "B.Fab")
			(hide yes)
			(effects
				(font
					(size 1 1)
					(thickness 0.15)
				)
				(justify mirror)
			)
		)
		(sheetname "USB Debug, DP")
		(sheetfile "usb.kicad_sch")
		(attr smd exclude_from_pos_files exclude_from_bom dnp)
		(fp_rect
			(start -0.925 0.47)
			(end 0.925 -0.47)
			(stroke
				(width 0.05)
				(type default)
			)
			(fill none)
			(layer "B.CrtYd")
		)
		(fp_rect
			(start -0.5 0.25)
			(end 0.5 -0.25)
			(stroke
				(width 0.15)
				(type solid)
			)
			(fill none)
			(layer "B.Fab")
		)
		(fp_text user "${REFERENCE}"
			(at -0.95 -3.168 -90)
			(layer "B.Fab")
			(hide yes)
			(effects
				(font
					(size 0.7 0.7)
					(thickness 0.15)
				)
				(justify left bottom mirror)
			)
		)
		(fp_text user "Author: Antmicro"
			(at -0.95 -4.169 -90)
			(layer "B.Fab")
			(hide yes)
			(effects
				(font
					(size 0.7 0.7)
					(thickness 0.15)
				)
				(justify left bottom mirror)
			)
		)
		(fp_text user "License: Apache-2.0"
			(at -0.95 -5.169 -90)
			(layer "B.Fab")
			(hide yes)
			(effects
				(font
					(size 0.7 0.7)
					(thickness 0.15)
				)
				(justify left bottom mirror)
			)
		)
		(pad "1" smd roundrect
			(at -0.48 0 90)
			(size 0.59 0.64)
			(layers "B.Cu" "B.Paste" "B.Mask")
			(roundrect_rratio 0.25)
			(net 305 "/USB Debug, DP/USBC0_SSEQ0")
			(pintype "passive")
		)
		(pad "2" smd roundrect
			(at 0.48 0 90)
			(size 0.59 0.64)
			(layers "B.Cu" "B.Paste" "B.Mask")
			(roundrect_rratio 0.25)
			(net 87 "+3V3")
			(pintype "passive")
		)
	)
	(footprint "antmicro-footprints:C_0402_1005Metric"
		(layer "B.Cu")
		(at 73.5 108.2)
		(descr "Capacitor SMD 0402")
		(tags "capacitor SMD 0402")
		(property "Reference" "C148"
			(at -0.17 2.25 180)
			(layer "B.SilkS")
			(effects
				(font
					(size 0.7 0.7)
					(thickness 0.15)
				)
				(justify left bottom mirror)
			)
		)
		(property "Value" "C_4u7_25V_0402"
			(at 0 -1.4 180)
			(layer "B.Fab")
			(effects
				(font
					(size 0.7 0.7)
					(thickness 0.15)
				)
				(justify left bottom mirror)
			)
		)
		(property "Footprint" "antmicro-footprints:C_0402_1005Metric"
			(at 0 0 0)
			(layer "F.Fab")
			(hide yes)
			(effects
				(font
					(size 1.27 1.27)
					(thickness 0.15)
				)
			)
		)
		(property "Datasheet" "https://www.murata.com/products/productdetail?partno=GRM155C61E475ME15%23"
			(at 0 0 0)
			(layer "F.Fab")
			(hide yes)
			(effects
				(font
					(size 1.27 1.27)
					(thickness 0.15)
				)
			)
		)
		(property "Author" "Antmicro"
			(at 0 0 0)
			(layer "B.Fab")
			(hide yes)
			(effects
				(font
					(size 1 1)
					(thickness 0.15)
				)
				(justify mirror)
			)
		)
		(property "Dielectric" "X5S"
			(at 0 0 0)
			(layer "B.Fab")
			(hide yes)
			(effects
				(font
					(size 1 1)
					(thickness 0.15)
				)
				(justify mirror)
			)
		)
		(property "License" "Apache-2.0"
			(at 0 0 0)
			(layer "B.Fab")
			(hide yes)
			(effects
				(font
					(size 1 1)
					(thickness 0.15)
				)
				(justify mirror)
			)
		)
		(property "MPN" "GRM155C61E475ME15J"
			(at 0 0 0)
			(layer "B.Fab")
			(hide yes)
			(effects
				(font
					(size 1 1)
					(thickness 0.15)
				)
				(justify mirror)
			)
		)
		(property "Manufacturer" "Murata"
			(at 0 0 0)
			(layer "B.Fab")
			(hide yes)
			(effects
				(font
					(size 1 1)
					(thickness 0.15)
				)
				(justify mirror)
			)
		)
		(property "Val" "4u7"
			(at 0 0 0)
			(layer "B.Fab")
			(hide yes)
			(effects
				(font
					(size 1 1)
					(thickness 0.15)
				)
				(justify mirror)
			)
		)
		(property "Voltage" "25V"
			(at 0 0 0)
			(layer "B.Fab")
			(hide yes)
			(effects
				(font
					(size 1 1)
					(thickness 0.15)
				)
				(justify mirror)
			)
		)
		(sheetname "USB Debug, DP")
		(sheetfile "usb.kicad_sch")
		(attr smd)
		(fp_rect
			(start -0.925 0.47)
			(end 0.925 -0.47)
			(stroke
				(width 0.05)
				(type default)
			)
			(fill none)
			(layer "B.CrtYd")
		)
		(fp_line
			(start -0.494 -0.248)
			(end 0.504 -0.248)
			(stroke
				(width 0.15)
				(type solid)
			)
			(layer "B.Fab")
		)
		(fp_line
			(start -0.494 0.25)
			(end -0.494 -0.248)
			(stroke
				(width 0.15)
				(type solid)
			)
			(layer "B.Fab")
		)
		(fp_line
			(start 0.504 -0.248)
			(end 0.504 0.25)
			(stroke
				(width 0.15)
				(type solid)
			)
			(layer "B.Fab")
		)
		(fp_line
			(start 0.504 0.25)
			(end -0.494 0.25)
			(stroke
				(width 0.15)
				(type solid)
			)
			(layer "B.Fab")
		)
		(fp_text user "License: Apache-2.0"
			(at -0.932 -5.17 180)
			(layer "B.Fab")
			(hide yes)
			(effects
				(font
					(size 0.7 0.7)
					(thickness 0.15)
				)
				(justify left bottom mirror)
			)
		)
		(fp_text user "${REFERENCE}"
			(at -0.932 -3.168 180)
			(layer "B.Fab")
			(hide yes)
			(effects
				(font
					(size 0.7 0.7)
					(thickness 0.15)
				)
				(justify left bottom mirror)
			)
		)
		(fp_text user "Author: Antmicro"
			(at -0.932 -4.17 180)
			(layer "B.Fab")
			(hide yes)
			(effects
				(font
					(size 0.7 0.7)
					(thickness 0.15)
				)
				(justify left bottom mirror)
			)
		)
		(pad "1" smd roundrect
			(at -0.48 0)
			(size 0.59 0.64)
			(layers "B.Cu" "B.Paste" "B.Mask")
			(roundrect_rratio 0.25)
			(net 481 "USBPD2_HV")
			(pintype "passive")
		)
		(pad "2" smd roundrect
			(at 0.48 0)
			(size 0.59 0.64)
			(layers "B.Cu" "B.Paste" "B.Mask")
			(roundrect_rratio 0.25)
			(net 1 "GND")
			(pintype "passive")
		)
	)
	(footprint "antmicro-footprints:R_0402_1005Metric"
		(layer "B.Cu")
		(at 72.3 105.2)
		(descr "Resistor SMD 0402")
		(tags "resistor SMD 0402")
		(property "Reference" "R82"
			(at -0.25 2.2 180)
			(layer "B.SilkS")
			(effects
				(font
					(size 0.7 0.7)
					(thickness 0.15)
				)
				(justify left bottom mirror)
			)
		)
		(property "Value" "R_0R_0402"
			(at 0 -1.4 180)
			(layer "B.Fab")
			(effects
				(font
					(size 0.7 0.7)
					(thickness 0.15)
				)
				(justify left bottom mirror)
			)
		)
		(property "Footprint" "antmicro-footprints:R_0402_1005Metric"
			(at 0 0 0)
			(layer "F.Fab")
			(hide yes)
			(effects
				(font
					(size 1.27 1.27)
					(thickness 0.15)
				)
			)
		)
		(property "Datasheet" "https://industrial.panasonic.com/cdbs/www-data/pdf/RDA0000/AOA0000C301.pdf"
			(at 0 0 0)
			(layer "F.Fab")
			(hide yes)
			(effects
				(font
					(size 1.27 1.27)
					(thickness 0.15)
				)
			)
		)
		(property "Author" "Antmicro"
			(at 0 0 0)
			(layer "B.Fab")
			(hide yes)
			(effects
				(font
					(size 1 1)
					(thickness 0.15)
				)
				(justify mirror)
			)
		)
		(property "Current" "1A"
			(at 0 0 0)
			(layer "B.Fab")
			(hide yes)
			(effects
				(font
					(size 1 1)
					(thickness 0.15)
				)
				(justify mirror)
			)
		)
		(property "License" "Apache-2.0"
			(at 0 0 0)
			(layer "B.Fab")
			(hide yes)
			(effects
				(font
					(size 1 1)
					(thickness 0.15)
				)
				(justify mirror)
			)
		)
		(property "MPN" "ERJ2GE0R00X"
			(at 0 0 0)
			(layer "B.Fab")
			(hide yes)
			(effects
				(font
					(size 1 1)
					(thickness 0.15)
				)
				(justify mirror)
			)
		)
		(property "Manufacturer" "Panasonic"
			(at 0 0 0)
			(layer "B.Fab")
			(hide yes)
			(effects
				(font
					(size 1 1)
					(thickness 0.15)
				)
				(justify mirror)
			)
		)
		(property "Tolerance" ""
			(at 0 0 0)
			(layer "B.Fab")
			(hide yes)
			(effects
				(font
					(size 1 1)
					(thickness 0.15)
				)
				(justify mirror)
			)
		)
		(property "Val" "0R"
			(at 0 0 0)
			(layer "B.Fab")
			(hide yes)
			(effects
				(font
					(size 1 1)
					(thickness 0.15)
				)
				(justify mirror)
			)
		)
		(sheetname "USB Debug, DP")
		(sheetfile "usb.kicad_sch")
		(attr smd exclude_from_pos_files exclude_from_bom dnp)
		(fp_rect
			(start -0.925 0.47)
			(end 0.925 -0.47)
			(stroke
				(width 0.05)
				(type default)
			)
			(fill none)
			(layer "B.CrtYd")
		)
		(fp_rect
			(start -0.5 0.25)
			(end 0.5 -0.25)
			(stroke
				(width 0.15)
				(type solid)
			)
			(fill none)
			(layer "B.Fab")
		)
		(fp_text user "${REFERENCE}"
			(at -0.95 -3.168 180)
			(layer "B.Fab")
			(hide yes)
			(effects
				(font
					(size 0.7 0.7)
					(thickness 0.15)
				)
				(justify left bottom mirror)
			)
		)
		(fp_text user "License: Apache-2.0"
			(at -0.95 -5.169 180)
			(layer "B.Fab")
			(hide yes)
			(effects
				(font
					(size 0.7 0.7)
					(thickness 0.15)
				)
				(justify left bottom mirror)
			)
		)
		(fp_text user "Author: Antmicro"
			(at -0.95 -4.169 180)
			(layer "B.Fab")
			(hide yes)
			(effects
				(font
					(size 0.7 0.7)
					(thickness 0.15)
				)
				(justify left bottom mirror)
			)
		)
		(pad "1" smd roundrect
			(at -0.48 0)
			(size 0.59 0.64)
			(layers "B.Cu" "B.Paste" "B.Mask")
			(roundrect_rratio 0.25)
			(net 293 "/USB Debug, DP/USBC0_FLIP")
			(pintype "passive")
		)
		(pad "2" smd roundrect
			(at 0.48 0)
			(size 0.59 0.64)
			(layers "B.Cu" "B.Paste" "B.Mask")
			(roundrect_rratio 0.25)
			(net 252 "SYS_SCL")
			(pintype "passive")
		)
	)
	(footprint "antmicro-footprints:R_0402_1005Metric"
		(layer "B.Cu")
		(at 112.4 106.1)
		(descr "Resistor SMD 0402")
		(tags "resistor SMD 0402")
		(property "Reference" "R113"
			(at 3.71 0.36 180)
			(layer "B.SilkS")
			(effects
				(font
					(size 0.7 0.7)
					(thickness 0.15)
				)
				(justify left bottom mirror)
			)
		)
		(property "Value" "R_0R_0402"
			(at 0 -1.4 180)
			(layer "B.Fab")
			(effects
				(font
					(size 0.7 0.7)
					(thickness 0.15)
				)
				(justify left bottom mirror)
			)
		)
		(property "Footprint" "antmicro-footprints:R_0402_1005Metric"
			(at 0 0 0)
			(layer "F.Fab")
			(hide yes)
			(effects
				(font
					(size 1.27 1.27)
					(thickness 0.15)
				)
			)
		)
		(property "Datasheet" "https://industrial.panasonic.com/cdbs/www-data/pdf/RDA0000/AOA0000C301.pdf"
			(at 0 0 0)
			(layer "F.Fab")
			(hide yes)
			(effects
				(font
					(size 1.27 1.27)
					(thickness 0.15)
				)
			)
		)
		(property "Author" "Antmicro"
			(at 0 0 0)
			(layer "B.Fab")
			(hide yes)
			(effects
				(font
					(size 1 1)
					(thickness 0.15)
				)
				(justify mirror)
			)
		)
		(property "Current" "1A"
			(at 0 0 0)
			(layer "B.Fab")
			(hide yes)
			(effects
				(font
					(size 1 1)
					(thickness 0.15)
				)
				(justify mirror)
			)
		)
		(property "License" "Apache-2.0"
			(at 0 0 0)
			(layer "B.Fab")
			(hide yes)
			(effects
				(font
					(size 1 1)
					(thickness 0.15)
				)
				(justify mirror)
			)
		)
		(property "MPN" "ERJ2GE0R00X"
			(at 0 0 0)
			(layer "B.Fab")
			(hide yes)
			(effects
				(font
					(size 1 1)
					(thickness 0.15)
				)
				(justify mirror)
			)
		)
		(property "Manufacturer" "Panasonic"
			(at 0 0 0)
			(layer "B.Fab")
			(hide yes)
			(effects
				(font
					(size 1 1)
					(thickness 0.15)
				)
				(justify mirror)
			)
		)
		(property "Tolerance" ""
			(at 0 0 0)
			(layer "B.Fab")
			(hide yes)
			(effects
				(font
					(size 1 1)
					(thickness 0.15)
				)
				(justify mirror)
			)
		)
		(property "Val" "0R"
			(at 0 0 0)
			(layer "B.Fab")
			(hide yes)
			(effects
				(font
					(size 1 1)
					(thickness 0.15)
				)
				(justify mirror)
			)
		)
		(sheetname "USB3")
		(sheetfile "usb3.kicad_sch")
		(attr smd exclude_from_pos_files exclude_from_bom dnp)
		(fp_rect
			(start -0.925 0.47)
			(end 0.925 -0.47)
			(stroke
				(width 0.05)
				(type default)
			)
			(fill none)
			(layer "B.CrtYd")
		)
		(fp_rect
			(start -0.5 0.25)
			(end 0.5 -0.25)
			(stroke
				(width 0.15)
				(type solid)
			)
			(fill none)
			(layer "B.Fab")
		)
		(fp_text user "${REFERENCE}"
			(at -0.95 -3.168 180)
			(layer "B.Fab")
			(hide yes)
			(effects
				(font
					(size 0.7 0.7)
					(thickness 0.15)
				)
				(justify left bottom mirror)
			)
		)
		(fp_text user "License: Apache-2.0"
			(at -0.95 -5.169 180)
			(layer "B.Fab")
			(hide yes)
			(effects
				(font
					(size 0.7 0.7)
					(thickness 0.15)
				)
				(justify left bottom mirror)
			)
		)
		(fp_text user "Author: Antmicro"
			(at -0.95 -4.169 180)
			(layer "B.Fab")
			(hide yes)
			(effects
				(font
					(size 0.7 0.7)
					(thickness 0.15)
				)
				(justify left bottom mirror)
			)
		)
		(pad "1" smd roundrect
			(at -0.48 0)
			(size 0.59 0.64)
			(layers "B.Cu" "B.Paste" "B.Mask")
			(roundrect_rratio 0.25)
			(net 314 "/USB3/USBC1_ADDR")
			(pintype "passive")
		)
		(pad "2" smd roundrect
			(at 0.48 0)
			(size 0.59 0.64)
			(layers "B.Cu" "B.Paste" "B.Mask")
			(roundrect_rratio 0.25)
			(net 99 "+5V")
			(pintype "passive")
		)
	)
	(footprint "antmicro-footprints:R_0402_1005Metric"
		(layer "B.Cu")
		(at 55.125 88.425)
		(descr "Resistor SMD 0402")
		(tags "resistor SMD 0402")
		(property "Reference" "R153"
			(at -1.245 2.555 0)
			(layer "B.SilkS")
			(effects
				(font
					(size 0.7 0.7)
					(thickness 0.15)
				)
				(justify right top mirror)
			)
		)
		(property "Value" "R_10k_0402"
			(at 0 -1.4 0)
			(layer "B.Fab")
			(effects
				(font
					(size 0.7 0.7)
					(thickness 0.15)
				)
				(justify right top mirror)
			)
		)
		(property "Footprint" "antmicro-footprints:R_0402_1005Metric"
			(at 0 0 0)
			(layer "F.Fab")
			(hide yes)
			(effects
				(font
					(size 1.27 1.27)
					(thickness 0.15)
				)
			)
		)
		(property "Datasheet" "https://www.bourns.com/docs/product-datasheets/cr.pdf"
			(at 0 0 0)
			(layer "F.Fab")
			(hide yes)
			(effects
				(font
					(size 1.27 1.27)
					(thickness 0.15)
				)
			)
		)
		(property "Author" "Antmicro"
			(at -33.575 143.225 90)
			(layer "B.Fab")
			(hide yes)
			(effects
				(font
					(size 1 1)
					(thickness 0.15)
				)
				(justify mirror)
			)
		)
		(property "License" "Apache-2.0"
			(at -33.575 143.225 90)
			(layer "B.Fab")
			(hide yes)
			(effects
				(font
					(size 1 1)
					(thickness 0.15)
				)
				(justify mirror)
			)
		)
		(property "MPN" "CR0402-FX-1002GLF"
			(at -33.575 143.225 90)
			(layer "B.Fab")
			(hide yes)
			(effects
				(font
					(size 1 1)
					(thickness 0.15)
				)
				(justify mirror)
			)
		)
		(property "Manufacturer" "Bourns"
			(at -33.575 143.225 90)
			(layer "B.Fab")
			(hide yes)
			(effects
				(font
					(size 1 1)
					(thickness 0.15)
				)
				(justify mirror)
			)
		)
		(property "Tolerance" "1%"
			(at -33.575 143.225 90)
			(layer "B.Fab")
			(hide yes)
			(effects
				(font
					(size 1 1)
					(thickness 0.15)
				)
				(justify mirror)
			)
		)
		(property "Val" "10k"
			(at -33.575 143.225 90)
			(layer "B.Fab")
			(hide yes)
			(effects
				(font
					(size 1 1)
					(thickness 0.15)
				)
				(justify mirror)
			)
		)
		(sheetname "Ethernet")
		(sheetfile "ethernet.kicad_sch")
		(attr smd exclude_from_pos_files exclude_from_bom dnp)
		(fp_rect
			(start -0.925 0.47)
			(end 0.925 -0.47)
			(stroke
				(width 0.05)
				(type default)
			)
			(fill none)
			(layer "B.CrtYd")
		)
		(fp_rect
			(start -0.5 0.25)
			(end 0.5 -0.25)
			(stroke
				(width 0.15)
				(type solid)
			)
			(fill none)
			(layer "B.Fab")
		)
		(fp_text user "${REFERENCE}"
			(at -0.95 -3.168 0)
			(layer "B.Fab")
			(hide yes)
			(effects
				(font
					(size 0.7 0.7)
					(thickness 0.15)
				)
				(justify right top mirror)
			)
		)
		(fp_text user "Author: Antmicro"
			(at -0.95 -4.169 0)
			(layer "B.Fab")
			(hide yes)
			(effects
				(font
					(size 0.7 0.7)
					(thickness 0.15)
				)
				(justify right top mirror)
			)
		)
		(fp_text user "License: Apache-2.0"
			(at -0.95 -5.169 0)
			(layer "B.Fab")
			(hide yes)
			(effects
				(font
					(size 0.7 0.7)
					(thickness 0.15)
				)
				(justify right top mirror)
			)
		)
		(pad "1" smd roundrect
			(at -0.48 0)
			(size 0.59 0.64)
			(layers "B.Cu" "B.Paste" "B.Mask")
			(roundrect_rratio 0.25)
			(net 574 "/Ethernet/~{BT}")
			(pintype "passive")
		)
		(pad "2" smd roundrect
			(at 0.48 0)
			(size 0.59 0.64)
			(layers "B.Cu" "B.Paste" "B.Mask")
			(roundrect_rratio 0.25)
			(net 105 "/Ethernet/VDD")
			(pintype "passive")
		)
	)
)
